# T6G (Grand Teton) — schematic netlist excerpt (pin names and nets, part order shuffled) for the footprints in the layout excerpt that follows; sources: Cadence DE-HDL packaged netlist, KiCad conversion of 04192023_DAF0TMB3IC0_F0TG_MB_C_brd_V02_OCP.brd

PL67  Q_INDUCTOR4P_14  150NH IND  pkg L_TLM117513Q-151QL_11X7-5XA  page 223
  \1\  = SW_PVDDIO_P1_SW4
  \2\  = IND_PVDDIO_P1_CPL0
  \3\  = IND_PVDDIO_P1_CPL4
  \4\  = PVDDIO_P1

PR3822  Q_RES  5.36K 1% CHIP  pkg 0402LF  page 140 : A = P3V3_OCP_CB_2 ; B = GND
R637  Q_RES  51.1 1% EMPTY  pkg 0201LF  page 342 : A = CLK_100M_RETIMER_CPU1_P2_DN ; B = GND

(kicad_pcb
	(version 20260206)
	(generator "pcbnew")
	(generator_version "10.0")
	(general
		(thickness 1.6)
		(legacy_teardrops no)
	)
	(paper "A4")
	(title_block
		(title "04192023_DAF0TMB3IC0_F0TG_MB_C_brd_V02_OCP.brd")
		(comment 1 "Grand Teton / footprints 3932-3934 of 8354")
	)
	(layers
		(0 "F.Cu" signal "TOP")
		(4 "In1.Cu" signal "GND")
		(6 "In2.Cu" signal "IN1")
		(8 "In3.Cu" signal "GND1")
		(10 "In4.Cu" signal "IN2")
		(12 "In5.Cu" signal "GND2")
		(14 "In6.Cu" signal "IN3")
		(16 "In7.Cu" signal "GND3")
		(18 "In8.Cu" signal "VCC")
		(20 "In9.Cu" signal "VCC1")
		(22 "In10.Cu" signal "GND4")
		(24 "In11.Cu" signal "IN4")
		(26 "In12.Cu" signal "GND5")
		(28 "In13.Cu" signal "IN5")
		(30 "In14.Cu" signal "GND6")
		(32 "In15.Cu" signal "IN6")
		(34 "In16.Cu" signal "GND7")
		(2 "B.Cu" signal "BOTTOM")
		(9 "F.Adhes" user "F.Adhesive")
		(11 "B.Adhes" user "B.Adhesive")
		(13 "F.Paste" user "Package Geometry/Pastemask Top")
		(15 "B.Paste" user "Package Geometry/Pastemask Bottom")
		(5 "F.SilkS" user "Ref Des/Silkscreen Top")
		(7 "B.SilkS" user "Ref Des/Silkscreen Bottom")
		(1 "F.Mask" user "Board Geometry/Soldermask Top")
		(3 "B.Mask" user "Board Geometry/Soldermask Bottom")
		(17 "Dwgs.User" user "User.Drawings")
		(19 "Cmts.User" user "User.Comments")
		(21 "Eco1.User" user "User.Eco1")
		(23 "Eco2.User" user "User.Eco2")
		(25 "Edge.Cuts" user "Board Geometry/Outline")
		(27 "Margin" user)
		(31 "F.CrtYd" user "Package Geometry/Place Bound Top")
		(29 "B.CrtYd" user "Package Geometry/Place Bound Bottom")
		(35 "F.Fab" user "Ref Des/Assembly Top")
		(33 "B.Fab" user "Ref Des/Assembly Bottom")
	)
	(footprint ""
		(layer "F.Cu")
		(at 28.71851 -337.403948)
		(property "Reference" "PL67"
			(at -3.242056 -15.887446 0)
			(unlocked yes)
			(layer "F.SilkS")
			(effects
				(font
					(size 0.7874 0.5842)
					(thickness 0.1524)
				)
				(justify left)
			)
		)
		(property "Value" ""
			(at 0 0 0)
			(layer "F.Fab")
			(effects
				(font
					(size 1.27 1.27)
				)
			)
		)
		(duplicate_pad_numbers_are_jumpers no)
		(fp_line
			(start -3.750056 -5.500116)
			(end -2.393442 -5.500116)
			(stroke
				(width 0.1524)
				(type default)
			)
			(layer "F.SilkS")
		)
		(fp_line
			(start -3.750056 5.500116)
			(end -3.750056 -5.500116)
			(stroke
				(width 0.1524)
				(type default)
			)
			(layer "F.SilkS")
		)
		(fp_line
			(start -2.393442 5.500116)
			(end -3.750056 5.500116)
			(stroke
				(width 0.1524)
				(type default)
			)
			(layer "F.SilkS")
		)
		(fp_line
			(start 2.393442 5.500116)
			(end 3.750056 5.500116)
			(stroke
				(width 0.1524)
				(type default)
			)
			(layer "F.SilkS")
		)
		(fp_line
			(start 3.750056 -5.500116)
			(end 2.393442 -5.500116)
			(stroke
				(width 0.1524)
				(type default)
			)
			(layer "F.SilkS")
		)
		(fp_line
			(start 3.750056 5.500116)
			(end 3.750056 -5.500116)
			(stroke
				(width 0.1524)
				(type default)
			)
			(layer "F.SilkS")
		)
		(fp_poly
			(pts
				(xy -3.9116 -4.249928) (xy -4.2164 -4.097528) (xy -4.2164 -4.402328)
			)
			(stroke
				(width 0)
				(type default)
			)
			(fill yes)
			(layer "F.SilkS")
		)
		(fp_line
			(start -3.750056 -5.500116)
			(end -3.750056 5.500116)
			(stroke
				(width 0.1)
				(type default)
			)
			(layer "F.Fab")
		)
		(fp_line
			(start -3.750056 5.500116)
			(end 3.750056 5.500116)
			(stroke
				(width 0.1)
				(type default)
			)
			(layer "F.Fab")
		)
		(fp_line
			(start 3.750056 -5.500116)
			(end -3.750056 -5.500116)
			(stroke
				(width 0.1)
				(type default)
			)
			(layer "F.Fab")
		)
		(fp_line
			(start 3.750056 5.500116)
			(end 3.750056 -5.500116)
			(stroke
				(width 0.1)
				(type default)
			)
			(layer "F.Fab")
		)
		(fp_poly
			(pts
				(xy -4.9276 -4.757928) (xy -4.9276 -3.741928) (xy -3.9116 -4.249928)
			)
			(stroke
				(width 0)
				(type default)
			)
			(fill yes)
			(layer "F.Fab")
		)
		(pad "1" smd rect
			(at 0 -4.249928 270)
			(size 2.413 4.5212)
			(layers "F.Cu" "F.Mask" "F.Paste")
			(net "SW_PVDDIO_P1_SW4")
		)
		(pad "2" smd rect
			(at 0 -1.175004 270)
			(size 1.3716 4.5212)
			(layers "F.Cu" "F.Mask" "F.Paste")
			(net "IND_PVDDIO_P1_CPL0")
		)
		(pad "3" smd rect
			(at 0 1.175004 270)
			(size 1.3716 4.5212)
			(layers "F.Cu" "F.Mask" "F.Paste")
			(net "IND_PVDDIO_P1_CPL4")
		)
		(pad "4" smd rect
			(at 0 4.249928 270)
			(size 2.413 4.5212)
			(layers "F.Cu" "F.Mask" "F.Paste")
			(net "PVDDIO_P1")
		)
	)
	(footprint ""
		(layer "F.Cu")
		(at 143.171672 -386.684774 -90)
		(property "Reference" "R637"
			(at 0 0 270)
			(layer "F.SilkS")
			(hide yes)
			(effects
				(font
					(size 1.27 1.27)
				)
			)
		)
		(property "Value" ""
			(at 0 0 270)
			(layer "F.Fab")
			(effects
				(font
					(size 1.27 1.27)
				)
			)
		)
		(duplicate_pad_numbers_are_jumpers no)
		(fp_line
			(start -0.32512 0.175006)
			(end -0.32512 -0.175006)
			(stroke
				(width 0.1)
				(type default)
			)
			(layer "F.Fab")
		)
		(fp_line
			(start 0.32512 0.175006)
			(end -0.32512 0.175006)
			(stroke
				(width 0.1)
				(type default)
			)
			(layer "F.Fab")
		)
		(fp_line
			(start -0.32512 -0.175006)
			(end 0.32512 -0.175006)
			(stroke
				(width 0.1)
				(type default)
			)
			(layer "F.Fab")
		)
		(fp_line
			(start 0.32512 -0.175006)
			(end 0.32512 0.175006)
			(stroke
				(width 0.1)
				(type default)
			)
			(layer "F.Fab")
		)
		(pad "1" smd rect
			(at -0.2667 0 270)
			(size 0.3048 0.381)
			(layers "F.Cu" "F.Mask" "F.Paste")
			(net "CLK_100M_RETIMER_CPU1_P2_DN")
		)
		(pad "2" smd rect
			(at 0.2667 0 90)
			(size 0.3048 0.381)
			(layers "F.Cu" "F.Mask" "F.Paste")
			(net "GND")
		)
	)
	(footprint ""
		(layer "F.Cu")
		(at 95.26143 -58.07583)
		(property "Reference" "PR3822"
			(at 0 0 0)
			(layer "F.SilkS")
			(hide yes)
			(effects
				(font
					(size 1.27 1.27)
				)
			)
		)
		(property "Value" ""
			(at 0 0 0)
			(layer "F.Fab")
			(effects
				(font
					(size 1.27 1.27)
				)
			)
		)
		(duplicate_pad_numbers_are_jumpers no)
		(fp_line
			(start -0.7874 -0.4064)
			(end 0.7874 -0.4064)
			(stroke
				(width 0.1524)
				(type default)
			)
			(layer "F.SilkS")
		)
		(fp_line
			(start -0.7874 0.4064)
			(end -0.7874 -0.4064)
			(stroke
				(width 0.1524)
				(type default)
			)
			(layer "F.SilkS")
		)
		(fp_line
			(start 0.7874 -0.4064)
			(end 0.7874 0.4064)
			(stroke
				(width 0.1524)
				(type default)
			)
			(layer "F.SilkS")
		)
		(fp_line
			(start 0.7874 0.4064)
			(end -0.7874 0.4064)
			(stroke
				(width 0.1524)
				(type default)
			)
			(layer "F.SilkS")
		)
		(fp_line
			(start -0.67945 -0.305054)
			(end -0.12065 -0.305054)
			(stroke
				(width 0.1)
				(type default)
			)
			(layer "F.Fab")
		)
		(fp_line
			(start -0.67945 0.3048)
			(end -0.67945 -0.305054)
			(stroke
				(width 0.1)
				(type default)
			)
			(layer "F.Fab")
		)
		(fp_line
			(start -0.12065 -0.305054)
			(end -0.12065 -0.2794)
			(stroke
				(width 0.1)
				(type default)
			)
			(layer "F.Fab")
		)
		(fp_line
			(start -0.12065 -0.2794)
			(end 0.12065 -0.2794)
			(stroke
				(width 0.1)
				(type default)
			)
			(layer "F.Fab")
		)
		(fp_line
			(start -0.12065 0.2794)
			(end -0.12065 0.3048)
			(stroke
				(width 0.1)
				(type default)
			)
			(layer "F.Fab")
		)
		(fp_line
			(start -0.12065 0.3048)
			(end -0.67945 0.3048)
			(stroke
				(width 0.1)
				(type default)
			)
			(layer "F.Fab")
		)
		(fp_line
			(start 0.120396 0.2794)
			(end -0.12065 0.2794)
			(stroke
				(width 0.1)
				(type default)
			)
			(layer "F.Fab")
		)
		(fp_line
			(start 0.120396 0.3048)
			(end 0.120396 0.2794)
			(stroke
				(width 0.1)
				(type default)
			)
			(layer "F.Fab")
		)
		(fp_line
			(start 0.12065 -0.3048)
			(end 0.67945 -0.3048)
			(stroke
				(width 0.1)
				(type default)
			)
			(layer "F.Fab")
		)
		(fp_line
			(start 0.12065 -0.2794)
			(end 0.12065 -0.3048)
			(stroke
				(width 0.1)
				(type default)
			)
			(layer "F.Fab")
		)
		(fp_line
			(start 0.67945 -0.3048)
			(end 0.67945 0.3048)
			(stroke
				(width 0.1)
				(type default)
			)
			(layer "F.Fab")
		)
		(fp_line
			(start 0.67945 0.3048)
			(end 0.120396 0.3048)
			(stroke
				(width 0.1)
				(type default)
			)
			(layer "F.Fab")
		)
		(pad "1" smd circle
			(at -0.40005 0)
			(size 0 0)
			(layers "F.Cu" "F.Mask" "F.Paste")
			(net "P3V3_OCP_CB_2")
		)
		(pad "2" smd circle
			(at 0.40005 0)
			(size 0 0)
			(layers "F.Cu" "F.Mask" "F.Paste")
			(net "GND")
		)
	)
)
